(kicad_pcb
	(version 20241229)
	(generator "pcbnew")
	(generator_version "9.0")
	(general
		(thickness 1.61)
		(legacy_teardrops no)
	)
	(paper "A3")
	(title_block
		(title "RDIMM DDR5 Tester")
		(date "2026-05-21")
		(rev "2.2.0")
		(company "Antmicro")
		(comment 9 "footprints 455-459 of 796")
	)
	(layers
		(0 "F.Cu" signal)
		(4 "In1.Cu" power)
		(6 "In2.Cu" mixed)
		(8 "In3.Cu" power)
		(10 "In4.Cu" mixed)
		(12 "In5.Cu" power)
		(14 "In6.Cu" mixed)
		(16 "In7.Cu" power)
		(18 "In8.Cu" power)
		(20 "In9.Cu" mixed)
		(22 "In10.Cu" power)
		(2 "B.Cu" signal)
		(9 "F.Adhes" user "F.Adhesive")
		(11 "B.Adhes" user "B.Adhesive")
		(13 "F.Paste" user)
		(15 "B.Paste" user)
		(5 "F.SilkS" user "F.Silkscreen")
		(7 "B.SilkS" user "B.Silkscreen")
		(1 "F.Mask" user)
		(3 "B.Mask" user)
		(17 "Dwgs.User" user "User.Drawings")
		(19 "Cmts.User" user "User.Comments")
		(21 "Eco1.User" user "User.Eco1")
		(23 "Eco2.User" user "User.Eco2")
		(25 "Edge.Cuts" user)
		(27 "Margin" user)
		(31 "F.CrtYd" user "F.Courtyard")
		(29 "B.CrtYd" user "B.Courtyard")
		(35 "F.Fab" user)
		(33 "B.Fab" user)
	)
	(footprint "antmicro-footprints:C_0402_1005Metric_EIA"
		(layer "B.Cu")
		(at 194 148.5 90)
		(descr "Capacitor SMD 0402 (1005 Metric), square (rectangular) end terminal, IPC_7351 nominal, (Body size source: IPC-SM-782 page 76, https://www.pcb-3d.com/wordpress/wp-content/uploads/ipc-sm-782a_amendment_1_and_2.pdf)")
		(tags "capacitor 0402")
		(property "Reference" "C58"
			(at 9.475 -30.675 90)
			(layer "B.SilkS")
			(effects
				(font
					(size 0.7 0.7)
					(thickness 0.15)
				)
				(justify right bottom mirror)
			)
		)
		(property "Value" "C_1u_25V_0402"
			(at 0 -1.169 90)
			(layer "B.Fab")
			(effects
				(font
					(size 0.7 0.7)
					(thickness 0.15)
				)
				(justify right bottom mirror)
			)
		)
		(property "Datasheet" "https://www.murata.com/products/productdetail?partno=GRM155R61E105KE11%23"
			(at 0 0 90)
			(layer "F.Fab")
			(hide yes)
			(effects
				(font
					(size 1.27 1.27)
					(thickness 0.15)
				)
			)
		)
		(property "MPN" "GRM155R61E105KE11J"
			(at 0 0 90)
			(unlocked yes)
			(layer "B.Fab")
			(hide yes)
			(effects
				(font
					(size 1 1)
					(thickness 0.15)
				)
				(justify mirror)
			)
		)
		(property "Manufacturer" "Murata"
			(at 0 0 90)
			(unlocked yes)
			(layer "B.Fab")
			(hide yes)
			(effects
				(font
					(size 1 1)
					(thickness 0.15)
				)
				(justify mirror)
			)
		)
		(property "License" "Apache-2.0"
			(at 0 0 90)
			(unlocked yes)
			(layer "B.Fab")
			(hide yes)
			(effects
				(font
					(size 1 1)
					(thickness 0.15)
				)
				(justify mirror)
			)
		)
		(property "Author" "Antmicro"
			(at 0 0 90)
			(unlocked yes)
			(layer "B.Fab")
			(hide yes)
			(effects
				(font
					(size 1 1)
					(thickness 0.15)
				)
				(justify mirror)
			)
		)
		(property "Val" "1u"
			(at 0 0 90)
			(unlocked yes)
			(layer "B.Fab")
			(hide yes)
			(effects
				(font
					(size 1 1)
					(thickness 0.15)
				)
				(justify mirror)
			)
		)
		(property "Voltage" "25V"
			(at 0 0 90)
			(unlocked yes)
			(layer "B.Fab")
			(hide yes)
			(effects
				(font
					(size 1 1)
					(thickness 0.15)
				)
				(justify mirror)
			)
		)
		(property "Dielectric" "X5R"
			(at 0 0 90)
			(unlocked yes)
			(layer "B.Fab")
			(hide yes)
			(effects
				(font
					(size 1 1)
					(thickness 0.15)
				)
				(justify mirror)
			)
		)
		(sheetname "/FPGA power/")
		(sheetfile "fpga-power.kicad_sch")
		(attr smd)
		(fp_rect
			(start -0.95 0.45)
			(end 0.95 -0.45)
			(stroke
				(width 0.05)
				(type default)
			)
			(fill no)
			(layer "B.CrtYd")
		)
		(fp_line
			(start 0.498 -0.248)
			(end -0.5 -0.248)
			(stroke
				(width 0.15)
				(type solid)
			)
			(layer "B.Fab")
		)
		(fp_line
			(start -0.5 -0.248)
			(end -0.5 0.25)
			(stroke
				(width 0.15)
				(type solid)
			)
			(layer "B.Fab")
		)
		(fp_line
			(start 0.498 0.25)
			(end 0.498 -0.248)
			(stroke
				(width 0.15)
				(type solid)
			)
			(layer "B.Fab")
		)
		(fp_line
			(start -0.5 0.25)
			(end 0.498 0.25)
			(stroke
				(width 0.15)
				(type solid)
			)
			(layer "B.Fab")
		)
		(fp_text user "${REFERENCE}"
			(at -0.9656 -3.169 270)
			(layer "B.Fab")
			(effects
				(font
					(size 0.7 0.7)
					(thickness 0.15)
				)
				(justify left bottom mirror)
			)
		)
		(fp_text user "License: Apache-2.0"
			(at -0.9656 -4.369 270)
			(layer "B.Fab")
			(effects
				(font
					(size 0.7 0.7)
					(thickness 0.15)
				)
				(justify left bottom mirror)
			)
		)
		(fp_text user "Author: Antmicro"
			(at -0.9656 -5.569 270)
			(layer "B.Fab")
			(effects
				(font
					(size 0.7 0.7)
					(thickness 0.15)
				)
				(justify left bottom mirror)
			)
		)
		(pad "1" smd roundrect
			(at -0.5 0)
			(size 0.6 0.6)
			(layers "B.Cu" "B.Mask" "B.Paste")
			(roundrect_rratio 0.25)
			(net 1 "GND")
			(pintype "passive")
		)
		(pad "2" smd roundrect
			(at 0.498 0 90)
			(size 0.6 0.6)
			(layers "B.Cu" "B.Mask" "B.Paste")
			(roundrect_rratio 0.25)
			(net 553 "+0V85")
			(pintype "passive")
		)
	)
	(footprint "antmicro-footprints:C_0402_1005Metric_EIA"
		(layer "B.Cu")
		(at 198.5 159)
		(descr "Capacitor SMD 0402 (1005 Metric), square (rectangular) end terminal, IPC_7351 nominal, (Body size source: IPC-SM-782 page 76, https://www.pcb-3d.com/wordpress/wp-content/uploads/ipc-sm-782a_amendment_1_and_2.pdf)")
		(tags "capacitor 0402")
		(property "Reference" "C168"
			(at -31.7 -10.3 0)
			(layer "B.SilkS")
			(effects
				(font
					(size 0.7 0.7)
					(thickness 0.15)
				)
				(justify right bottom mirror)
			)
		)
		(property "Value" "C_10u_10V_0402"
			(at 0 -1.169 0)
			(layer "B.Fab")
			(effects
				(font
					(size 0.7 0.7)
					(thickness 0.15)
				)
				(justify right bottom mirror)
			)
		)
		(property "Datasheet" "https://www.murata.com/products/productdetail?partno=GRM155R61A106ME11%23"
			(at 0 0 0)
			(layer "F.Fab")
			(hide yes)
			(effects
				(font
					(size 1.27 1.27)
					(thickness 0.15)
				)
			)
		)
		(property "MPN" "GRM155R61A106ME11D"
			(at 0 0 0)
			(unlocked yes)
			(layer "B.Fab")
			(hide yes)
			(effects
				(font
					(size 1 1)
					(thickness 0.15)
				)
				(justify mirror)
			)
		)
		(property "Manufacturer" "Murata"
			(at 0 0 0)
			(unlocked yes)
			(layer "B.Fab")
			(hide yes)
			(effects
				(font
					(size 1 1)
					(thickness 0.15)
				)
				(justify mirror)
			)
		)
		(property "License" "Apache-2.0"
			(at 0 0 0)
			(unlocked yes)
			(layer "B.Fab")
			(hide yes)
			(effects
				(font
					(size 1 1)
					(thickness 0.15)
				)
				(justify mirror)
			)
		)
		(property "Author" "Antmicro"
			(at 0 0 0)
			(unlocked yes)
			(layer "B.Fab")
			(hide yes)
			(effects
				(font
					(size 1 1)
					(thickness 0.15)
				)
				(justify mirror)
			)
		)
		(property "Val" "10u"
			(at 0 0 0)
			(unlocked yes)
			(layer "B.Fab")
			(hide yes)
			(effects
				(font
					(size 1 1)
					(thickness 0.15)
				)
				(justify mirror)
			)
		)
		(property "Voltage" "10V"
			(at 0 0 0)
			(unlocked yes)
			(layer "B.Fab")
			(hide yes)
			(effects
				(font
					(size 1 1)
					(thickness 0.15)
				)
				(justify mirror)
			)
		)
		(property "Dielectric" "X5R"
			(at 0 0 0)
			(unlocked yes)
			(layer "B.Fab")
			(hide yes)
			(effects
				(font
					(size 1 1)
					(thickness 0.15)
				)
				(justify mirror)
			)
		)
		(sheetname "/FPGA power/")
		(sheetfile "fpga-power.kicad_sch")
		(attr smd)
		(fp_rect
			(start -0.95 0.45)
			(end 0.95 -0.45)
			(stroke
				(width 0.05)
				(type default)
			)
			(fill no)
			(layer "B.CrtYd")
		)
		(fp_line
			(start -0.5 -0.248)
			(end -0.5 0.25)
			(stroke
				(width 0.15)
				(type solid)
			)
			(layer "B.Fab")
		)
		(fp_line
			(start -0.5 0.25)
			(end 0.498 0.25)
			(stroke
				(width 0.15)
				(type solid)
			)
			(layer "B.Fab")
		)
		(fp_line
			(start 0.498 -0.248)
			(end -0.5 -0.248)
			(stroke
				(width 0.15)
				(type solid)
			)
			(layer "B.Fab")
		)
		(fp_line
			(start 0.498 0.25)
			(end 0.498 -0.248)
			(stroke
				(width 0.15)
				(type solid)
			)
			(layer "B.Fab")
		)
		(fp_text user "${REFERENCE}"
			(at -0.9656 -3.169 180)
			(layer "B.Fab")
			(effects
				(font
					(size 0.7 0.7)
					(thickness 0.15)
				)
				(justify left bottom mirror)
			)
		)
		(fp_text user "Author: Antmicro"
			(at -0.9656 -5.569 180)
			(layer "B.Fab")
			(effects
				(font
					(size 0.7 0.7)
					(thickness 0.15)
				)
				(justify left bottom mirror)
			)
		)
		(fp_text user "License: Apache-2.0"
			(at -0.9656 -4.369 180)
			(layer "B.Fab")
			(effects
				(font
					(size 0.7 0.7)
					(thickness 0.15)
				)
				(justify left bottom mirror)
			)
		)
		(pad "1" smd roundrect
			(at -0.5 0 270)
			(size 0.6 0.6)
			(layers "B.Cu" "B.Mask" "B.Paste")
			(roundrect_rratio 0.25)
			(net 1 "GND")
			(pintype "passive")
		)
		(pad "2" smd roundrect
			(at 0.498 0)
			(size 0.6 0.6)
			(layers "B.Cu" "B.Mask" "B.Paste")
			(roundrect_rratio 0.25)
			(net 820 "+0V9_MGTAVCC")
			(pintype "passive")
		)
	)
	(footprint "antmicro-footprints:R_0402_1005Metric_EIA"
		(layer "B.Cu")
		(at 201 141.5 90)
		(descr "Resistor SMD 0402 (1005 Metric), square (rectangular) end terminal, IPC_7351 nominal, (Body size source: IPC-SM-782 page 76, https://www.pcb-3d.com/wordpress/wp-content/uploads/ipc-sm-782a_amendment_1_and_2.pdf)")
		(tags "resistor 0402")
		(property "Reference" "R133"
			(at 1.425 1.625 270)
			(layer "B.SilkS")
			(effects
				(font
					(size 0.7 0.7)
					(thickness 0.15)
				)
				(justify left bottom mirror)
			)
		)
		(property "Value" "R_240R_0402"
			(at 0 -1.169 270)
			(layer "B.Fab")
			(effects
				(font
					(size 0.7 0.7)
					(thickness 0.15)
				)
				(justify left bottom mirror)
			)
		)
		(property "Datasheet" "https://www.bourns.com/docs/product-datasheets/cr.pdf"
			(at 0 0 90)
			(layer "F.Fab")
			(hide yes)
			(effects
				(font
					(size 1.27 1.27)
					(thickness 0.15)
				)
			)
		)
		(property "MPN" "CR0402-FX-2400GLF"
			(at 0 0 90)
			(unlocked yes)
			(layer "B.Fab")
			(hide yes)
			(effects
				(font
					(size 1 1)
					(thickness 0.15)
				)
				(justify mirror)
			)
		)
		(property "Manufacturer" "Bourns"
			(at 0 0 90)
			(unlocked yes)
			(layer "B.Fab")
			(hide yes)
			(effects
				(font
					(size 1 1)
					(thickness 0.15)
				)
				(justify mirror)
			)
		)
		(property "License" "Apache-2.0"
			(at 0 0 90)
			(unlocked yes)
			(layer "B.Fab")
			(hide yes)
			(effects
				(font
					(size 1 1)
					(thickness 0.15)
				)
				(justify mirror)
			)
		)
		(property "Author" "Antmicro"
			(at 0 0 90)
			(unlocked yes)
			(layer "B.Fab")
			(hide yes)
			(effects
				(font
					(size 1 1)
					(thickness 0.15)
				)
				(justify mirror)
			)
		)
		(property "Val" "240R"
			(at 0 0 90)
			(unlocked yes)
			(layer "B.Fab")
			(hide yes)
			(effects
				(font
					(size 1 1)
					(thickness 0.15)
				)
				(justify mirror)
			)
		)
		(property "Tolerance" "1%"
			(at 0 0 90)
			(unlocked yes)
			(layer "B.Fab")
			(hide yes)
			(effects
				(font
					(size 1 1)
					(thickness 0.15)
				)
				(justify mirror)
			)
		)
		(sheetname "/FPGA banks HP/")
		(sheetfile "fpga-hp-banks.kicad_sch")
		(attr smd)
		(fp_rect
			(start -0.95 0.45)
			(end 0.95 -0.45)
			(stroke
				(width 0.05)
				(type default)
			)
			(fill no)
			(layer "B.CrtYd")
		)
		(fp_line
			(start 0.499 -0.249)
			(end -0.5 -0.249)
			(stroke
				(width 0.15)
				(type solid)
			)
			(layer "B.Fab")
		)
		(fp_line
			(start -0.5 -0.249)
			(end -0.5 0.25)
			(stroke
				(width 0.15)
				(type solid)
			)
			(layer "B.Fab")
		)
		(fp_line
			(start 0.499 0.25)
			(end 0.499 -0.249)
			(stroke
				(width 0.15)
				(type solid)
			)
			(layer "B.Fab")
		)
		(fp_line
			(start -0.5 0.25)
			(end 0.499 0.25)
			(stroke
				(width 0.15)
				(type solid)
			)
			(layer "B.Fab")
		)
		(fp_text user "Author: Antmicro"
			(at -0.95 -5.569 270)
			(layer "B.Fab")
			(effects
				(font
					(size 0.7 0.7)
					(thickness 0.15)
				)
				(justify left bottom mirror)
			)
		)
		(fp_text user "${REFERENCE}"
			(at -0.95 -3.169 270)
			(layer "B.Fab")
			(effects
				(font
					(size 0.7 0.7)
					(thickness 0.15)
				)
				(justify left bottom mirror)
			)
		)
		(fp_text user "License: Apache-2.0"
			(at -0.95 -4.369 270)
			(layer "B.Fab")
			(effects
				(font
					(size 0.7 0.7)
					(thickness 0.15)
				)
				(justify left bottom mirror)
			)
		)
		(pad "1" smd roundrect
			(at -0.5 0)
			(size 0.6 0.6)
			(layers "B.Cu" "B.Mask" "B.Paste")
			(roundrect_rratio 0.25)
			(net 547 "/FPGA banks HP/VRP_64")
			(pintype "passive")
		)
		(pad "2" smd roundrect
			(at 0.499 0 90)
			(size 0.6 0.6)
			(layers "B.Cu" "B.Mask" "B.Paste")
			(roundrect_rratio 0.25)
			(net 1 "GND")
			(pintype "passive")
		)
	)
	(footprint "antmicro-footprints:C_0402_1005Metric"
		(layer "B.Cu")
		(at 120.125 159.45 -90)
		(descr "Capacitor SMD 0402")
		(tags "capacitor SMD 0402")
		(property "Reference" "C298"
			(at 0.9 -0.525 90)
			(layer "B.SilkS")
			(effects
				(font
					(size 0.7 0.7)
					(thickness 0.15)
				)
				(justify left bottom mirror)
			)
		)
		(property "Value" "C_100n_0402"
			(at -1.022927 -2.155213 90)
			(layer "B.Fab")
			(effects
				(font
					(size 0.7 0.7)
					(thickness 0.15)
				)
				(justify left bottom mirror)
			)
		)
		(property "Datasheet" "https://www.murata.com/products/productdetail?partno=GRM155R61H104KE14%23"
			(at 0 0 270)
			(layer "F.Fab")
			(hide yes)
			(effects
				(font
					(size 1.27 1.27)
					(thickness 0.15)
				)
			)
		)
		(property "MPN" "GRM155R61H104KE14D"
			(at 0 0 270)
			(unlocked yes)
			(layer "B.Fab")
			(hide yes)
			(effects
				(font
					(size 1 1)
					(thickness 0.15)
				)
				(justify mirror)
			)
		)
		(property "Manufacturer" "Murata"
			(at 0 0 270)
			(unlocked yes)
			(layer "B.Fab")
			(hide yes)
			(effects
				(font
					(size 1 1)
					(thickness 0.15)
				)
				(justify mirror)
			)
		)
		(property "License" "Apache-2.0"
			(at 0 0 270)
			(unlocked yes)
			(layer "B.Fab")
			(hide yes)
			(effects
				(font
					(size 1 1)
					(thickness 0.15)
				)
				(justify mirror)
			)
		)
		(property "Author" "Antmicro"
			(at 0 0 270)
			(unlocked yes)
			(layer "B.Fab")
			(hide yes)
			(effects
				(font
					(size 1 1)
					(thickness 0.15)
				)
				(justify mirror)
			)
		)
		(property "Val" "100n"
			(at 0 0 270)
			(unlocked yes)
			(layer "B.Fab")
			(hide yes)
			(effects
				(font
					(size 1 1)
					(thickness 0.15)
				)
				(justify mirror)
			)
		)
		(property "Voltage" "50V"
			(at 0 0 270)
			(unlocked yes)
			(layer "B.Fab")
			(hide yes)
			(effects
				(font
					(size 1 1)
					(thickness 0.15)
				)
				(justify mirror)
			)
		)
		(property "Dielectric" "X5R"
			(at 0 0 270)
			(unlocked yes)
			(layer "B.Fab")
			(hide yes)
			(effects
				(font
					(size 1 1)
					(thickness 0.15)
				)
				(justify mirror)
			)
		)
		(sheetname "/HDMI + SD Card/")
		(sheetfile "hdmi-sd-card.kicad_sch")
		(attr smd)
		(fp_rect
			(start -0.925 0.47)
			(end 0.925 -0.47)
			(stroke
				(width 0.05)
				(type default)
			)
			(fill no)
			(layer "B.CrtYd")
		)
		(fp_line
			(start -0.494 0.25)
			(end 0.504 0.25)
			(stroke
				(width 0.15)
				(type solid)
			)
			(layer "B.Fab")
		)
		(fp_line
			(start 0.504 0.25)
			(end 0.504 -0.248)
			(stroke
				(width 0.15)
				(type solid)
			)
			(layer "B.Fab")
		)
		(fp_line
			(start -0.494 -0.248)
			(end -0.494 0.25)
			(stroke
				(width 0.15)
				(type solid)
			)
			(layer "B.Fab")
		)
		(fp_line
			(start 0.504 -0.248)
			(end -0.494 -0.248)
			(stroke
				(width 0.15)
				(type solid)
			)
			(layer "B.Fab")
		)
		(fp_text user "License: Apache-2.0"
			(at -0.939 -5.799 90)
			(layer "B.Fab")
			(effects
				(font
					(size 0.7 0.7)
					(thickness 0.15)
				)
				(justify left bottom mirror)
			)
		)
		(fp_text user "Author: Antmicro"
			(at -0.939 -3.399 90)
			(layer "B.Fab")
			(effects
				(font
					(size 0.7 0.7)
					(thickness 0.15)
				)
				(justify left bottom mirror)
			)
		)
		(fp_text user "${REFERENCE}"
			(at -0.939 -4.599 90)
			(layer "B.Fab")
			(effects
				(font
					(size 0.7 0.7)
					(thickness 0.15)
				)
				(justify left bottom mirror)
			)
		)
		(pad "1" smd roundrect
			(at -0.48 0 270)
			(size 0.59 0.64)
			(layers "B.Cu" "B.Mask" "B.Paste")
			(roundrect_rratio 0.25)
			(net 1 "GND")
			(pintype "passive")
		)
		(pad "2" smd roundrect
			(at 0.48 0 270)
			(size 0.59 0.64)
			(layers "B.Cu" "B.Mask" "B.Paste")
			(roundrect_rratio 0.25)
			(net 797 "+1V8")
			(pintype "passive")
		)
	)
	(footprint "antmicro-footprints:R_0402_1005Metric"
		(layer "B.Cu")
		(at 188.4 104.2)
		(descr "Resistor SMD 0402")
		(tags "resistor SMD 0402")
		(property "Reference" "R26"
			(at 1.01 1.76 0)
			(layer "B.SilkS")
			(effects
				(font
					(size 0.7 0.7)
					(thickness 0.15)
				)
				(justify right bottom mirror)
			)
		)
		(property "Value" "R_0R_0402"
			(at -1.011843 -1.772047 0)
			(layer "B.Fab")
			(effects
				(font
					(size 0.7 0.7)
					(thickness 0.15)
				)
				(justify right bottom mirror)
			)
		)
		(property "Datasheet" "https://industrial.panasonic.com/cdbs/www-data/pdf/RDA0000/AOA0000C301.pdf"
			(at 0 0 0)
			(layer "F.Fab")
			(hide yes)
			(effects
				(font
					(size 1.27 1.27)
					(thickness 0.15)
				)
			)
		)
		(property "MPN" "ERJ2GE0R00X"
			(at 0 0 0)
			(unlocked yes)
			(layer "B.Fab")
			(hide yes)
			(effects
				(font
					(size 1 1)
					(thickness 0.15)
				)
				(justify mirror)
			)
		)
		(property "Manufacturer" "Panasonic"
			(at 0 0 0)
			(unlocked yes)
			(layer "B.Fab")
			(hide yes)
			(effects
				(font
					(size 1 1)
					(thickness 0.15)
				)
				(justify mirror)
			)
		)
		(property "License" "Apache-2.0"
			(at 0 0 0)
			(unlocked yes)
			(layer "B.Fab")
			(hide yes)
			(effects
				(font
					(size 1 1)
					(thickness 0.15)
				)
				(justify mirror)
			)
		)
		(property "Author" "Antmicro"
			(at 0 0 0)
			(unlocked yes)
			(layer "B.Fab")
			(hide yes)
			(effects
				(font
					(size 1 1)
					(thickness 0.15)
				)
				(justify mirror)
			)
		)
		(property "Val" "0R"
			(at 0 0 0)
			(unlocked yes)
			(layer "B.Fab")
			(hide yes)
			(effects
				(font
					(size 1 1)
					(thickness 0.15)
				)
				(justify mirror)
			)
		)
		(property "Tolerance" "~"
			(at 0 0 0)
			(unlocked yes)
			(layer "B.Fab")
			(hide yes)
			(effects
				(font
					(size 1 1)
					(thickness 0.15)
				)
				(justify mirror)
			)
		)
		(property "Current" "1A"
			(at 0 0 0)
			(unlocked yes)
			(layer "B.Fab")
			(hide yes)
			(effects
				(font
					(size 1 1)
					(thickness 0.15)
				)
				(justify mirror)
			)
		)
		(sheetname "/DDR5 RDIMM/")
		(sheetfile "ddr5-rdimm.kicad_sch")
		(attr smd exclude_from_bom dnp)
		(fp_rect
			(start -0.925 0.47)
			(end 0.925 -0.47)
			(stroke
				(width 0.05)
				(type default)
			)
			(fill no)
			(layer "B.CrtYd")
		)
		(fp_rect
			(start -0.5 0.25)
			(end 0.5 -0.25)
			(stroke
				(width 0.15)
				(type solid)
			)
			(fill no)
			(layer "B.Fab")
		)
		(fp_text user "${REFERENCE}"
			(at -0.95 -3.168 180)
			(layer "B.Fab")
			(effects
				(font
					(size 0.7 0.7)
					(thickness 0.15)
				)
				(justify left bottom mirror)
			)
		)
		(fp_text user "Author: Antmicro"
			(at -0.95 -4.169 180)
			(layer "B.Fab")
			(effects
				(font
					(size 0.7 0.7)
					(thickness 0.15)
				)
				(justify left bottom mirror)
			)
		)
		(fp_text user "License: Apache-2.0"
			(at -0.95 -5.169 180)
			(layer "B.Fab")
			(effects
				(font
					(size 0.7 0.7)
					(thickness 0.15)
				)
				(justify left bottom mirror)
			)
		)
		(pad "1" smd roundrect
			(at -0.48 0)
			(size 0.59 0.64)
			(layers "B.Cu" "B.Mask" "B.Paste")
			(roundrect_rratio 0.25)
			(net 1 "GND")
			(pintype "passive")
		)
		(pad "2" smd roundrect
			(at 0.48 0)
			(size 0.59 0.64)
			(layers "B.Cu" "B.Mask" "B.Paste")
			(roundrect_rratio 0.25)
			(net 703 "/DDR5 RDIMM/VSS_DET1")
			(pintype "passive")
		)
	)
)
